# T6G (Grand Teton) — schematic netlist excerpt (pin names and nets, part order shuffled) for the footprints in the layout excerpt that follows; sources: Cadence DE-HDL packaged netlist, KiCad conversion of 04192023_DAF0TMB3IC0_F0TG_MB_C_brd_V02_OCP.brd

R1260  Q_RES  0 5% EMPTY  pkg 0402LF  page 258 : A = P5V_AUX_ADC ; B = P5V_AUX_ADC_MAM
R3168  Q_RES  0 5% CHIP  pkg 0402LF  page 137 : A = OCP_V3_2_MAIN_PWR_EN ; B = OCP_V3_2_MAIN_PWR_EN_R

(kicad_pcb
	(version 20260206)
	(generator "pcbnew")
	(generator_version "10.0")
	(general
		(thickness 1.6)
		(legacy_teardrops no)
	)
	(paper "A4")
	(title_block
		(title "04192023_DAF0TMB3IC0_F0TG_MB_C_brd_V02_OCP.brd")
		(comment 1 "Grand Teton / footprints 7496-7497 of 8354")
	)
	(layers
		(0 "F.Cu" signal "TOP")
		(4 "In1.Cu" signal "GND")
		(6 "In2.Cu" signal "IN1")
		(8 "In3.Cu" signal "GND1")
		(10 "In4.Cu" signal "IN2")
		(12 "In5.Cu" signal "GND2")
		(14 "In6.Cu" signal "IN3")
		(16 "In7.Cu" signal "GND3")
		(18 "In8.Cu" signal "VCC")
		(20 "In9.Cu" signal "VCC1")
		(22 "In10.Cu" signal "GND4")
		(24 "In11.Cu" signal "IN4")
		(26 "In12.Cu" signal "GND5")
		(28 "In13.Cu" signal "IN5")
		(30 "In14.Cu" signal "GND6")
		(32 "In15.Cu" signal "IN6")
		(34 "In16.Cu" signal "GND7")
		(2 "B.Cu" signal "BOTTOM")
		(9 "F.Adhes" user "F.Adhesive")
		(11 "B.Adhes" user "B.Adhesive")
		(13 "F.Paste" user "Package Geometry/Pastemask Top")
		(15 "B.Paste" user "Package Geometry/Pastemask Bottom")
		(5 "F.SilkS" user "Ref Des/Silkscreen Top")
		(7 "B.SilkS" user "Ref Des/Silkscreen Bottom")
		(1 "F.Mask" user "Board Geometry/Soldermask Top")
		(3 "B.Mask" user "Board Geometry/Soldermask Bottom")
		(17 "Dwgs.User" user "User.Drawings")
		(19 "Cmts.User" user "User.Comments")
		(21 "Eco1.User" user "User.Eco1")
		(23 "Eco2.User" user "User.Eco2")
		(25 "Edge.Cuts" user "Board Geometry/Outline")
		(27 "Margin" user)
		(31 "F.CrtYd" user "Package Geometry/Place Bound Top")
		(29 "B.CrtYd" user "Package Geometry/Place Bound Bottom")
		(35 "F.Fab" user "Ref Des/Assembly Top")
		(33 "B.Fab" user "Ref Des/Assembly Bottom")
	)
	(footprint ""
		(layer "B.Cu")
		(at 231.914192 -321.775582 180)
		(property "Reference" "R1260"
			(at 0 0 0)
			(layer "B.SilkS")
			(hide yes)
			(effects
				(font
					(size 1.27 1.27)
				)
				(justify mirror)
			)
		)
		(property "Value" ""
			(at 0 0 0)
			(layer "B.Fab")
			(effects
				(font
					(size 1.27 1.27)
				)
				(justify mirror)
			)
		)
		(duplicate_pad_numbers_are_jumpers no)
		(fp_line
			(start 0.7874 0.4064)
			(end 0.7874 -0.4064)
			(stroke
				(width 0.1524)
				(type default)
			)
			(layer "B.SilkS")
		)
		(fp_line
			(start 0.7874 -0.4064)
			(end -0.7874 -0.4064)
			(stroke
				(width 0.1524)
				(type default)
			)
			(layer "B.SilkS")
		)
		(fp_line
			(start -0.7874 0.4064)
			(end 0.7874 0.4064)
			(stroke
				(width 0.1524)
				(type default)
			)
			(layer "B.SilkS")
		)
		(fp_line
			(start -0.7874 -0.4064)
			(end -0.7874 0.4064)
			(stroke
				(width 0.1524)
				(type default)
			)
			(layer "B.SilkS")
		)
		(fp_line
			(start 0.67945 0.3048)
			(end 0.67945 -0.305054)
			(stroke
				(width 0.1)
				(type default)
			)
			(layer "B.Fab")
		)
		(fp_line
			(start 0.67945 -0.305054)
			(end 0.12065 -0.305054)
			(stroke
				(width 0.1)
				(type default)
			)
			(layer "B.Fab")
		)
		(fp_line
			(start 0.12065 0.3048)
			(end 0.67945 0.3048)
			(stroke
				(width 0.1)
				(type default)
			)
			(layer "B.Fab")
		)
		(fp_line
			(start 0.12065 0.2794)
			(end 0.12065 0.3048)
			(stroke
				(width 0.1)
				(type default)
			)
			(layer "B.Fab")
		)
		(fp_line
			(start 0.12065 -0.2794)
			(end -0.12065 -0.2794)
			(stroke
				(width 0.1)
				(type default)
			)
			(layer "B.Fab")
		)
		(fp_line
			(start 0.12065 -0.305054)
			(end 0.12065 -0.2794)
			(stroke
				(width 0.1)
				(type default)
			)
			(layer "B.Fab")
		)
		(fp_line
			(start -0.120396 0.3048)
			(end -0.120396 0.2794)
			(stroke
				(width 0.1)
				(type default)
			)
			(layer "B.Fab")
		)
		(fp_line
			(start -0.120396 0.2794)
			(end 0.12065 0.2794)
			(stroke
				(width 0.1)
				(type default)
			)
			(layer "B.Fab")
		)
		(fp_line
			(start -0.12065 -0.2794)
			(end -0.12065 -0.3048)
			(stroke
				(width 0.1)
				(type default)
			)
			(layer "B.Fab")
		)
		(fp_line
			(start -0.12065 -0.3048)
			(end -0.67945 -0.3048)
			(stroke
				(width 0.1)
				(type default)
			)
			(layer "B.Fab")
		)
		(fp_line
			(start -0.67945 0.3048)
			(end -0.120396 0.3048)
			(stroke
				(width 0.1)
				(type default)
			)
			(layer "B.Fab")
		)
		(fp_line
			(start -0.67945 -0.3048)
			(end -0.67945 0.3048)
			(stroke
				(width 0.1)
				(type default)
			)
			(layer "B.Fab")
		)
		(pad "1" smd rect
			(at 0.40005 0 180)
			(size 0.4572 0.508)
			(layers "B.Cu" "B.Mask" "B.Paste")
			(net "P5V_AUX_ADC")
		)
		(pad "2" smd rect
			(at -0.40005 0 180)
			(size 0.4572 0.508)
			(layers "B.Cu" "B.Mask" "B.Paste")
			(net "P5V_AUX_ADC_MAM")
		)
	)
	(footprint ""
		(layer "B.Cu")
		(at 77.14488 -11.267948 90)
		(property "Reference" "R3168"
			(at 0 0 90)
			(layer "B.SilkS")
			(hide yes)
			(effects
				(font
					(size 1.27 1.27)
				)
				(justify mirror)
			)
		)
		(property "Value" ""
			(at 0 0 90)
			(layer "B.Fab")
			(effects
				(font
					(size 1.27 1.27)
				)
				(justify mirror)
			)
		)
		(duplicate_pad_numbers_are_jumpers no)
		(fp_line
			(start 0.7874 -0.4064)
			(end -0.7874 -0.4064)
			(stroke
				(width 0.1524)
				(type default)
			)
			(layer "B.SilkS")
		)
		(fp_line
			(start -0.7874 -0.4064)
			(end -0.7874 0.4064)
			(stroke
				(width 0.1524)
				(type default)
			)
			(layer "B.SilkS")
		)
		(fp_line
			(start 0.7874 0.4064)
			(end 0.7874 -0.4064)
			(stroke
				(width 0.1524)
				(type default)
			)
			(layer "B.SilkS")
		)
		(fp_line
			(start -0.7874 0.4064)
			(end 0.7874 0.4064)
			(stroke
				(width 0.1524)
				(type default)
			)
			(layer "B.SilkS")
		)
		(fp_line
			(start 0.67945 -0.305054)
			(end 0.12065 -0.305054)
			(stroke
				(width 0.1)
				(type default)
			)
			(layer "B.Fab")
		)
		(fp_line
			(start 0.12065 -0.305054)
			(end 0.12065 -0.2794)
			(stroke
				(width 0.1)
				(type default)
			)
			(layer "B.Fab")
		)
		(fp_line
			(start -0.12065 -0.3048)
			(end -0.67945 -0.3048)
			(stroke
				(width 0.1)
				(type default)
			)
			(layer "B.Fab")
		)
		(fp_line
			(start -0.67945 -0.3048)
			(end -0.67945 0.3048)
			(stroke
				(width 0.1)
				(type default)
			)
			(layer "B.Fab")
		)
		(fp_line
			(start 0.12065 -0.2794)
			(end -0.12065 -0.2794)
			(stroke
				(width 0.1)
				(type default)
			)
			(layer "B.Fab")
		)
		(fp_line
			(start -0.12065 -0.2794)
			(end -0.12065 -0.3048)
			(stroke
				(width 0.1)
				(type default)
			)
			(layer "B.Fab")
		)
		(fp_line
			(start 0.12065 0.2794)
			(end 0.12065 0.3048)
			(stroke
				(width 0.1)
				(type default)
			)
			(layer "B.Fab")
		)
		(fp_line
			(start -0.120396 0.2794)
			(end 0.12065 0.2794)
			(stroke
				(width 0.1)
				(type default)
			)
			(layer "B.Fab")
		)
		(fp_line
			(start 0.67945 0.3048)
			(end 0.67945 -0.305054)
			(stroke
				(width 0.1)
				(type default)
			)
			(layer "B.Fab")
		)
		(fp_line
			(start 0.12065 0.3048)
			(end 0.67945 0.3048)
			(stroke
				(width 0.1)
				(type default)
			)
			(layer "B.Fab")
		)
		(fp_line
			(start -0.120396 0.3048)
			(end -0.120396 0.2794)
			(stroke
				(width 0.1)
				(type default)
			)
			(layer "B.Fab")
		)
		(fp_line
			(start -0.67945 0.3048)
			(end -0.120396 0.3048)
			(stroke
				(width 0.1)
				(type default)
			)
			(layer "B.Fab")
		)
		(pad "1" smd circle
			(at 0.40005 0 270)
			(size 0 0)
			(layers "B.Cu" "B.Mask" "B.Paste")
			(net "OCP_V3_2_MAIN_PWR_EN")
		)
		(pad "2" smd circle
			(at -0.40005 0 270)
			(size 0 0)
			(layers "B.Cu" "B.Mask" "B.Paste")
			(net "OCP_V3_2_MAIN_PWR_EN_R")
		)
	)
)
